(kicad_pcb
	(version 20241229)
	(generator "pcbnew")
	(generator_version "9.0")
	(general
		(thickness 1.61)
		(legacy_teardrops no)
	)
	(paper "A3")
	(title_block
		(title "RDIMM DDR5 Tester")
		(date "2026-05-21")
		(rev "2.2.0")
		(company "Antmicro")
		(comment 9 "footprints 775-779 of 796")
	)
	(layers
		(0 "F.Cu" signal)
		(4 "In1.Cu" power)
		(6 "In2.Cu" mixed)
		(8 "In3.Cu" power)
		(10 "In4.Cu" mixed)
		(12 "In5.Cu" power)
		(14 "In6.Cu" mixed)
		(16 "In7.Cu" power)
		(18 "In8.Cu" power)
		(20 "In9.Cu" mixed)
		(22 "In10.Cu" power)
		(2 "B.Cu" signal)
		(9 "F.Adhes" user "F.Adhesive")
		(11 "B.Adhes" user "B.Adhesive")
		(13 "F.Paste" user)
		(15 "B.Paste" user)
		(5 "F.SilkS" user "F.Silkscreen")
		(7 "B.SilkS" user "B.Silkscreen")
		(1 "F.Mask" user)
		(3 "B.Mask" user)
		(17 "Dwgs.User" user "User.Drawings")
		(19 "Cmts.User" user "User.Comments")
		(21 "Eco1.User" user "User.Eco1")
		(23 "Eco2.User" user "User.Eco2")
		(25 "Edge.Cuts" user)
		(27 "Margin" user)
		(31 "F.CrtYd" user "F.Courtyard")
		(29 "B.CrtYd" user "B.Courtyard")
		(35 "F.Fab" user)
		(33 "B.Fab" user)
	)
	(footprint "antmicro-footprints:C_0603_1608Metric"
		(layer "B.Cu")
		(at 180.1 152.525)
		(descr "Capacitor SMD 0603")
		(tags "capacitor 0603")
		(property "Reference" "C22"
			(at -0.975 1.925 0)
			(layer "B.SilkS")
			(effects
				(font
					(size 0.7 0.7)
					(thickness 0.15)
				)
				(justify right bottom mirror)
			)
		)
		(property "Value" "C_47u_0603"
			(at -1.42757 -1.770288 0)
			(layer "B.Fab")
			(effects
				(font
					(size 0.7 0.7)
					(thickness 0.15)
				)
				(justify right bottom mirror)
			)
		)
		(property "Datasheet" "https://www.murata.com/products/productdetail?partno=GRM188R60J476ME15%23"
			(at 0 0 0)
			(layer "F.Fab")
			(hide yes)
			(effects
				(font
					(size 1.27 1.27)
					(thickness 0.15)
				)
			)
		)
		(property "Manufacturer" "Murata"
			(at 0 0 0)
			(unlocked yes)
			(layer "B.Fab")
			(hide yes)
			(effects
				(font
					(size 1 1)
					(thickness 0.15)
				)
				(justify mirror)
			)
		)
		(property "MPN" "GRM188R60J476ME15D"
			(at 0 0 0)
			(unlocked yes)
			(layer "B.Fab")
			(hide yes)
			(effects
				(font
					(size 1 1)
					(thickness 0.15)
				)
				(justify mirror)
			)
		)
		(property "Val" "47u"
			(at 0 0 0)
			(unlocked yes)
			(layer "B.Fab")
			(hide yes)
			(effects
				(font
					(size 1 1)
					(thickness 0.15)
				)
				(justify mirror)
			)
		)
		(property "License" "Apache-2.0"
			(at 0 0 0)
			(unlocked yes)
			(layer "B.Fab")
			(hide yes)
			(effects
				(font
					(size 1 1)
					(thickness 0.15)
				)
				(justify mirror)
			)
		)
		(property "Author" "Antmicro"
			(at 0 0 0)
			(unlocked yes)
			(layer "B.Fab")
			(hide yes)
			(effects
				(font
					(size 1 1)
					(thickness 0.15)
				)
				(justify mirror)
			)
		)
		(property "Voltage" ""
			(at 0 0 0)
			(unlocked yes)
			(layer "B.Fab")
			(hide yes)
			(effects
				(font
					(size 1 1)
					(thickness 0.15)
				)
				(justify mirror)
			)
		)
		(property "Dielectric" ""
			(at 0 0 0)
			(unlocked yes)
			(layer "B.Fab")
			(hide yes)
			(effects
				(font
					(size 1 1)
					(thickness 0.15)
				)
				(justify mirror)
			)
		)
		(sheetname "/FPGA power/")
		(sheetfile "fpga-power.kicad_sch")
		(attr smd)
		(fp_line
			(start -0.15 -0.4)
			(end 0.15 -0.4)
			(stroke
				(width 0.15)
				(type solid)
			)
			(layer "B.SilkS")
		)
		(fp_line
			(start -0.15 0.4)
			(end 0.15 0.4)
			(stroke
				(width 0.15)
				(type solid)
			)
			(layer "B.SilkS")
		)
		(fp_rect
			(start -1.25 0.65)
			(end 1.25 -0.65)
			(stroke
				(width 0.05)
				(type solid)
			)
			(fill no)
			(layer "B.CrtYd")
		)
		(fp_rect
			(start -0.8 0.4)
			(end 0.8 -0.4)
			(stroke
				(width 0.15)
				(type solid)
			)
			(fill no)
			(layer "B.Fab")
		)
		(fp_text user "Author: Antmicro"
			(at -1.682 -4.894 180)
			(layer "B.Fab")
			(effects
				(font
					(size 0.7 0.7)
					(thickness 0.15)
				)
				(justify left bottom mirror)
			)
		)
		(fp_text user "License: Apache-2.0"
			(at -1.682 -5.895 180)
			(layer "B.Fab")
			(effects
				(font
					(size 0.7 0.7)
					(thickness 0.15)
				)
				(justify left bottom mirror)
			)
		)
		(fp_text user "${REFERENCE}"
			(at -1.682 -3.895 180)
			(layer "B.Fab")
			(effects
				(font
					(size 0.7 0.7)
					(thickness 0.15)
				)
				(justify left bottom mirror)
			)
		)
		(pad "1" smd roundrect
			(at -0.7 0)
			(size 0.8 1)
			(layers "B.Cu" "B.Mask" "B.Paste")
			(roundrect_rratio 0.2)
			(net 151 "+3V3")
			(pintype "passive")
		)
		(pad "2" smd roundrect
			(at 0.7 0)
			(size 0.8 1)
			(layers "B.Cu" "B.Mask" "B.Paste")
			(roundrect_rratio 0.2)
			(net 1 "GND")
			(pintype "passive")
		)
	)
	(footprint "antmicro-footprints:R_0402_1005Metric"
		(layer "B.Cu")
		(at 238.451999 163.175)
		(descr "Resistor SMD 0402")
		(tags "resistor SMD 0402")
		(property "Reference" "R138"
			(at 1.173001 0.475 0)
			(layer "B.SilkS")
			(effects
				(font
					(size 0.7 0.7)
					(thickness 0.15)
				)
				(justify right bottom mirror)
			)
		)
		(property "Value" "R_0R_0402"
			(at -1.011843 -1.772047 0)
			(layer "B.Fab")
			(effects
				(font
					(size 0.7 0.7)
					(thickness 0.15)
				)
				(justify right bottom mirror)
			)
		)
		(property "Datasheet" "https://industrial.panasonic.com/cdbs/www-data/pdf/RDA0000/AOA0000C301.pdf"
			(at 0 0 0)
			(layer "F.Fab")
			(hide yes)
			(effects
				(font
					(size 1.27 1.27)
					(thickness 0.15)
				)
			)
		)
		(property "MPN" "ERJ2GE0R00X"
			(at 0 0 0)
			(unlocked yes)
			(layer "B.Fab")
			(hide yes)
			(effects
				(font
					(size 1 1)
					(thickness 0.15)
				)
				(justify mirror)
			)
		)
		(property "Manufacturer" "Panasonic"
			(at 0 0 0)
			(unlocked yes)
			(layer "B.Fab")
			(hide yes)
			(effects
				(font
					(size 1 1)
					(thickness 0.15)
				)
				(justify mirror)
			)
		)
		(property "License" "Apache-2.0"
			(at 0 0 0)
			(unlocked yes)
			(layer "B.Fab")
			(hide yes)
			(effects
				(font
					(size 1 1)
					(thickness 0.15)
				)
				(justify mirror)
			)
		)
		(property "Author" "Antmicro"
			(at 0 0 0)
			(unlocked yes)
			(layer "B.Fab")
			(hide yes)
			(effects
				(font
					(size 1 1)
					(thickness 0.15)
				)
				(justify mirror)
			)
		)
		(property "Val" "0R"
			(at 0 0 0)
			(unlocked yes)
			(layer "B.Fab")
			(hide yes)
			(effects
				(font
					(size 1 1)
					(thickness 0.15)
				)
				(justify mirror)
			)
		)
		(property "Tolerance" "~"
			(at 0 0 0)
			(unlocked yes)
			(layer "B.Fab")
			(hide yes)
			(effects
				(font
					(size 1 1)
					(thickness 0.15)
				)
				(justify mirror)
			)
		)
		(property "Current" "1A"
			(at 0 0 0)
			(unlocked yes)
			(layer "B.Fab")
			(hide yes)
			(effects
				(font
					(size 1 1)
					(thickness 0.15)
				)
				(justify mirror)
			)
		)
		(sheetname "/Supply/")
		(sheetfile "supply.kicad_sch")
		(attr smd)
		(fp_rect
			(start -0.925 0.47)
			(end 0.925 -0.47)
			(stroke
				(width 0.05)
				(type default)
			)
			(fill no)
			(layer "B.CrtYd")
		)
		(fp_rect
			(start -0.5 0.25)
			(end 0.5 -0.25)
			(stroke
				(width 0.15)
				(type solid)
			)
			(fill no)
			(layer "B.Fab")
		)
		(fp_text user "License: Apache-2.0"
			(at -0.95 -5.169 180)
			(layer "B.Fab")
			(effects
				(font
					(size 0.7 0.7)
					(thickness 0.15)
				)
				(justify left bottom mirror)
			)
		)
		(fp_text user "${REFERENCE}"
			(at -0.95 -3.168 180)
			(layer "B.Fab")
			(effects
				(font
					(size 0.7 0.7)
					(thickness 0.15)
				)
				(justify left bottom mirror)
			)
		)
		(fp_text user "Author: Antmicro"
			(at -0.95 -4.169 180)
			(layer "B.Fab")
			(effects
				(font
					(size 0.7 0.7)
					(thickness 0.15)
				)
				(justify left bottom mirror)
			)
		)
		(pad "1" smd roundrect
			(at -0.48 0)
			(size 0.59 0.64)
			(layers "B.Cu" "B.Mask" "B.Paste")
			(roundrect_rratio 0.25)
			(net 183 "POWER")
			(pintype "passive")
		)
		(pad "2" smd roundrect
			(at 0.48 0)
			(size 0.59 0.64)
			(layers "B.Cu" "B.Mask" "B.Paste")
			(roundrect_rratio 0.25)
			(net 485 "PG3")
			(pintype "passive")
		)
	)
	(footprint "antmicro-footprints:C_0402_1005Metric_EIA"
		(layer "B.Cu")
		(at 184 150.5 90)
		(descr "Capacitor SMD 0402 (1005 Metric), square (rectangular) end terminal, IPC_7351 nominal, (Body size source: IPC-SM-782 page 76, https://www.pcb-3d.com/wordpress/wp-content/uploads/ipc-sm-782a_amendment_1_and_2.pdf)")
		(tags "capacitor 0402")
		(property "Reference" "C13"
			(at 9.325 -30.625 90)
			(layer "B.SilkS")
			(effects
				(font
					(size 0.7 0.7)
					(thickness 0.15)
				)
				(justify right bottom mirror)
			)
		)
		(property "Value" "C_100n_0402"
			(at 0 -1.169 90)
			(layer "B.Fab")
			(effects
				(font
					(size 0.7 0.7)
					(thickness 0.15)
				)
				(justify right bottom mirror)
			)
		)
		(property "Datasheet" "https://www.murata.com/products/productdetail?partno=GRM155R61H104KE14%23"
			(at 0 0 90)
			(layer "F.Fab")
			(hide yes)
			(effects
				(font
					(size 1.27 1.27)
					(thickness 0.15)
				)
			)
		)
		(property "MPN" "GRM155R61H104KE14D"
			(at 0 0 90)
			(unlocked yes)
			(layer "B.Fab")
			(hide yes)
			(effects
				(font
					(size 1 1)
					(thickness 0.15)
				)
				(justify mirror)
			)
		)
		(property "Manufacturer" "Murata"
			(at 0 0 90)
			(unlocked yes)
			(layer "B.Fab")
			(hide yes)
			(effects
				(font
					(size 1 1)
					(thickness 0.15)
				)
				(justify mirror)
			)
		)
		(property "License" "Apache-2.0"
			(at 0 0 90)
			(unlocked yes)
			(layer "B.Fab")
			(hide yes)
			(effects
				(font
					(size 1 1)
					(thickness 0.15)
				)
				(justify mirror)
			)
		)
		(property "Author" "Antmicro"
			(at 0 0 90)
			(unlocked yes)
			(layer "B.Fab")
			(hide yes)
			(effects
				(font
					(size 1 1)
					(thickness 0.15)
				)
				(justify mirror)
			)
		)
		(property "Val" "100n"
			(at 0 0 90)
			(unlocked yes)
			(layer "B.Fab")
			(hide yes)
			(effects
				(font
					(size 1 1)
					(thickness 0.15)
				)
				(justify mirror)
			)
		)
		(property "Voltage" "50V"
			(at 0 0 90)
			(unlocked yes)
			(layer "B.Fab")
			(hide yes)
			(effects
				(font
					(size 1 1)
					(thickness 0.15)
				)
				(justify mirror)
			)
		)
		(property "Dielectric" "X5R"
			(at 0 0 90)
			(unlocked yes)
			(layer "B.Fab")
			(hide yes)
			(effects
				(font
					(size 1 1)
					(thickness 0.15)
				)
				(justify mirror)
			)
		)
		(sheetname "/FPGA power/")
		(sheetfile "fpga-power.kicad_sch")
		(attr smd)
		(fp_rect
			(start -0.95 0.45)
			(end 0.95 -0.45)
			(stroke
				(width 0.05)
				(type default)
			)
			(fill no)
			(layer "B.CrtYd")
		)
		(fp_line
			(start 0.498 -0.248)
			(end -0.5 -0.248)
			(stroke
				(width 0.15)
				(type solid)
			)
			(layer "B.Fab")
		)
		(fp_line
			(start -0.5 -0.248)
			(end -0.5 0.25)
			(stroke
				(width 0.15)
				(type solid)
			)
			(layer "B.Fab")
		)
		(fp_line
			(start 0.498 0.25)
			(end 0.498 -0.248)
			(stroke
				(width 0.15)
				(type solid)
			)
			(layer "B.Fab")
		)
		(fp_line
			(start -0.5 0.25)
			(end 0.498 0.25)
			(stroke
				(width 0.15)
				(type solid)
			)
			(layer "B.Fab")
		)
		(fp_text user "${REFERENCE}"
			(at -0.9656 -3.169 270)
			(layer "B.Fab")
			(effects
				(font
					(size 0.7 0.7)
					(thickness 0.15)
				)
				(justify left bottom mirror)
			)
		)
		(fp_text user "Author: Antmicro"
			(at -0.9656 -5.569 270)
			(layer "B.Fab")
			(effects
				(font
					(size 0.7 0.7)
					(thickness 0.15)
				)
				(justify left bottom mirror)
			)
		)
		(fp_text user "License: Apache-2.0"
			(at -0.9656 -4.369 270)
			(layer "B.Fab")
			(effects
				(font
					(size 0.7 0.7)
					(thickness 0.15)
				)
				(justify left bottom mirror)
			)
		)
		(pad "1" smd roundrect
			(at -0.5 0)
			(size 0.6 0.6)
			(layers "B.Cu" "B.Mask" "B.Paste")
			(roundrect_rratio 0.25)
			(net 1 "GND")
			(pintype "passive")
		)
		(pad "2" smd roundrect
			(at 0.498 0 90)
			(size 0.6 0.6)
			(layers "B.Cu" "B.Mask" "B.Paste")
			(roundrect_rratio 0.25)
			(net 553 "+0V85")
			(pintype "passive")
		)
	)
	(footprint "antmicro-footprints:R_0402_1005Metric"
		(layer "B.Cu")
		(at 252.924499 132.199 90)
		(descr "Resistor SMD 0402")
		(tags "resistor SMD 0402")
		(property "Reference" "R160"
			(at 1.329 -0.264499 90)
			(layer "B.SilkS")
			(effects
				(font
					(size 0.7 0.7)
					(thickness 0.15)
				)
				(justify right bottom mirror)
			)
		)
		(property "Value" "R_47k_0402"
			(at -1.011843 -1.772047 90)
			(layer "B.Fab")
			(effects
				(font
					(size 0.7 0.7)
					(thickness 0.15)
				)
				(justify right bottom mirror)
			)
		)
		(property "Datasheet" "https://www.bourns.com/docs/product-datasheets/cr.pdf"
			(at 0 0 90)
			(layer "F.Fab")
			(hide yes)
			(effects
				(font
					(size 1.27 1.27)
					(thickness 0.15)
				)
			)
		)
		(property "Manufacturer" "Bourns"
			(at 0 0 90)
			(unlocked yes)
			(layer "B.Fab")
			(hide yes)
			(effects
				(font
					(size 1 1)
					(thickness 0.15)
				)
				(justify mirror)
			)
		)
		(property "MPN" "CR0402-FX-4702GLF"
			(at 0 0 90)
			(unlocked yes)
			(layer "B.Fab")
			(hide yes)
			(effects
				(font
					(size 1 1)
					(thickness 0.15)
				)
				(justify mirror)
			)
		)
		(property "Val" "47k"
			(at 0 0 90)
			(unlocked yes)
			(layer "B.Fab")
			(hide yes)
			(effects
				(font
					(size 1 1)
					(thickness 0.15)
				)
				(justify mirror)
			)
		)
		(property "License" "Apache-2.0"
			(at 0 0 90)
			(unlocked yes)
			(layer "B.Fab")
			(hide yes)
			(effects
				(font
					(size 1 1)
					(thickness 0.15)
				)
				(justify mirror)
			)
		)
		(property "Author" "Antmicro"
			(at 0 0 90)
			(unlocked yes)
			(layer "B.Fab")
			(hide yes)
			(effects
				(font
					(size 1 1)
					(thickness 0.15)
				)
				(justify mirror)
			)
		)
		(property "Tolerance" "1%"
			(at 0 0 90)
			(unlocked yes)
			(layer "B.Fab")
			(hide yes)
			(effects
				(font
					(size 1 1)
					(thickness 0.15)
				)
				(justify mirror)
			)
		)
		(sheetname "/Supply/")
		(sheetfile "supply.kicad_sch")
		(attr smd)
		(fp_rect
			(start -0.925 0.47)
			(end 0.925 -0.47)
			(stroke
				(width 0.05)
				(type default)
			)
			(fill no)
			(layer "B.CrtYd")
		)
		(fp_rect
			(start -0.5 0.25)
			(end 0.5 -0.25)
			(stroke
				(width 0.15)
				(type solid)
			)
			(fill no)
			(layer "B.Fab")
		)
		(fp_text user "${REFERENCE}"
			(at -0.95 -3.168 270)
			(layer "B.Fab")
			(effects
				(font
					(size 0.7 0.7)
					(thickness 0.15)
				)
				(justify left bottom mirror)
			)
		)
		(fp_text user "License: Apache-2.0"
			(at -0.95 -5.169 270)
			(layer "B.Fab")
			(effects
				(font
					(size 0.7 0.7)
					(thickness 0.15)
				)
				(justify left bottom mirror)
			)
		)
		(fp_text user "Author: Antmicro"
			(at -0.95 -4.169 270)
			(layer "B.Fab")
			(effects
				(font
					(size 0.7 0.7)
					(thickness 0.15)
				)
				(justify left bottom mirror)
			)
		)
		(pad "1" smd roundrect
			(at -0.48 0 90)
			(size 0.59 0.64)
			(layers "B.Cu" "B.Mask" "B.Paste")
			(roundrect_rratio 0.25)
			(net 157 "/Supply/~{PB_CTRL_INT}")
			(pintype "passive")
		)
		(pad "2" smd roundrect
			(at 0.48 0 90)
			(size 0.59 0.64)
			(layers "B.Cu" "B.Mask" "B.Paste")
			(roundrect_rratio 0.25)
			(net 138 "/Supply/PB_CTRL_OUT")
			(pintype "passive")
		)
	)
	(footprint "antmicro-footprints:R_0402_1005Metric"
		(layer "B.Cu")
		(at 242.97 134.755 90)
		(descr "Resistor SMD 0402")
		(tags "resistor SMD 0402")
		(property "Reference" "R123"
			(at -3.805 0.33 90)
			(layer "B.SilkS")
			(effects
				(font
					(size 0.7 0.7)
					(thickness 0.15)
				)
				(justify right bottom mirror)
			)
		)
		(property "Value" "R_4k7_0402"
			(at -1.011843 -1.772047 90)
			(layer "B.Fab")
			(effects
				(font
					(size 0.7 0.7)
					(thickness 0.15)
				)
				(justify right bottom mirror)
			)
		)
		(property "Datasheet" "https://www.bourns.com/docs/product-datasheets/cr.pdf"
			(at 0 0 90)
			(layer "F.Fab")
			(hide yes)
			(effects
				(font
					(size 1.27 1.27)
					(thickness 0.15)
				)
			)
		)
		(property "Manufacturer" "Bourns"
			(at 0 0 90)
			(unlocked yes)
			(layer "B.Fab")
			(hide yes)
			(effects
				(font
					(size 1 1)
					(thickness 0.15)
				)
				(justify mirror)
			)
		)
		(property "MPN" "CR0402-FX-4701GLF"
			(at 0 0 90)
			(unlocked yes)
			(layer "B.Fab")
			(hide yes)
			(effects
				(font
					(size 1 1)
					(thickness 0.15)
				)
				(justify mirror)
			)
		)
		(property "Val" "4k7"
			(at 0 0 90)
			(unlocked yes)
			(layer "B.Fab")
			(hide yes)
			(effects
				(font
					(size 1 1)
					(thickness 0.15)
				)
				(justify mirror)
			)
		)
		(property "License" "Apache-2.0"
			(at 0 0 90)
			(unlocked yes)
			(layer "B.Fab")
			(hide yes)
			(effects
				(font
					(size 1 1)
					(thickness 0.15)
				)
				(justify mirror)
			)
		)
		(property "Author" "Antmicro"
			(at 0 0 90)
			(unlocked yes)
			(layer "B.Fab")
			(hide yes)
			(effects
				(font
					(size 1 1)
					(thickness 0.15)
				)
				(justify mirror)
			)
		)
		(property "Tolerance" "1%"
			(at 0 0 90)
			(unlocked yes)
			(layer "B.Fab")
			(hide yes)
			(effects
				(font
					(size 1 1)
					(thickness 0.15)
				)
				(justify mirror)
			)
		)
		(sheetname "/I^{2}C + I3C/")
		(sheetfile "i2c.kicad_sch")
		(attr smd)
		(fp_rect
			(start -0.925 0.47)
			(end 0.925 -0.47)
			(stroke
				(width 0.05)
				(type default)
			)
			(fill no)
			(layer "B.CrtYd")
		)
		(fp_rect
			(start -0.5 0.25)
			(end 0.5 -0.25)
			(stroke
				(width 0.15)
				(type solid)
			)
			(fill no)
			(layer "B.Fab")
		)
		(fp_text user "Author: Antmicro"
			(at -0.95 -4.169 270)
			(layer "B.Fab")
			(effects
				(font
					(size 0.7 0.7)
					(thickness 0.15)
				)
				(justify left bottom mirror)
			)
		)
		(fp_text user "${REFERENCE}"
			(at -0.95 -3.168 270)
			(layer "B.Fab")
			(effects
				(font
					(size 0.7 0.7)
					(thickness 0.15)
				)
				(justify left bottom mirror)
			)
		)
		(fp_text user "License: Apache-2.0"
			(at -0.95 -5.169 270)
			(layer "B.Fab")
			(effects
				(font
					(size 0.7 0.7)
					(thickness 0.15)
				)
				(justify left bottom mirror)
			)
		)
		(pad "1" smd roundrect
			(at -0.48 0 90)
			(size 0.59 0.64)
			(layers "B.Cu" "B.Mask" "B.Paste")
			(roundrect_rratio 0.25)
			(net 151 "+3V3")
			(pintype "passive")
		)
		(pad "2" smd roundrect
			(at 0.48 0 90)
			(size 0.59 0.64)
			(layers "B.Cu" "B.Mask" "B.Paste")
			(roundrect_rratio 0.25)
			(net 472 "/FPGA banks HD/FPGA_DDR.SDA")
			(pintype "passive")
		)
	)
)
